# T6G (Grand Teton) — schematic netlist excerpt (pin names and nets, part order shuffled) for the footprints in the layout excerpt that follows; sources: Cadence DE-HDL packaged netlist, KiCad conversion of 04192023_DAF0TMB3IC0_F0TG_MB_C_brd_V02_OCP.brd

C556  Q_CAP  100UF 4V 20% X6S  pkg C0805  page 279 : A = P0V9_CPU0_RT0_2A ; B = GND
PC115  Q_CAPP  390UF 2.5V 20% ALUM  pkg SMLF  page 209 : A = PVDD18_S5_P0 ; B = GND
C8019  Q_CAP  100NF 50V 10% X7R  pkg C0402  page 268 : A = P12V_AUX ; B = GND
TP14  TP  NA  pkg TP  page 54 : TP = VSENSE_PVDD18_S5_P1_DN

(kicad_pcb
	(version 20260206)
	(generator "pcbnew")
	(generator_version "10.0")
	(general
		(thickness 1.6)
		(legacy_teardrops no)
	)
	(paper "A4")
	(title_block
		(title "04192023_DAF0TMB3IC0_F0TG_MB_C_brd_V02_OCP.brd")
		(comment 1 "Grand Teton / footprints 3571-3574 of 8354")
	)
	(layers
		(0 "F.Cu" signal "TOP")
		(4 "In1.Cu" signal "GND")
		(6 "In2.Cu" signal "IN1")
		(8 "In3.Cu" signal "GND1")
		(10 "In4.Cu" signal "IN2")
		(12 "In5.Cu" signal "GND2")
		(14 "In6.Cu" signal "IN3")
		(16 "In7.Cu" signal "GND3")
		(18 "In8.Cu" signal "VCC")
		(20 "In9.Cu" signal "VCC1")
		(22 "In10.Cu" signal "GND4")
		(24 "In11.Cu" signal "IN4")
		(26 "In12.Cu" signal "GND5")
		(28 "In13.Cu" signal "IN5")
		(30 "In14.Cu" signal "GND6")
		(32 "In15.Cu" signal "IN6")
		(34 "In16.Cu" signal "GND7")
		(2 "B.Cu" signal "BOTTOM")
		(9 "F.Adhes" user "F.Adhesive")
		(11 "B.Adhes" user "B.Adhesive")
		(13 "F.Paste" user "Package Geometry/Pastemask Top")
		(15 "B.Paste" user "Package Geometry/Pastemask Bottom")
		(5 "F.SilkS" user "Ref Des/Silkscreen Top")
		(7 "B.SilkS" user "Ref Des/Silkscreen Bottom")
		(1 "F.Mask" user "Board Geometry/Soldermask Top")
		(3 "B.Mask" user "Board Geometry/Soldermask Bottom")
		(17 "Dwgs.User" user "User.Drawings")
		(19 "Cmts.User" user "User.Comments")
		(21 "Eco1.User" user "User.Eco1")
		(23 "Eco2.User" user "User.Eco2")
		(25 "Edge.Cuts" user "Board Geometry/Outline")
		(27 "Margin" user)
		(31 "F.CrtYd" user "Package Geometry/Place Bound Top")
		(29 "B.CrtYd" user "Package Geometry/Place Bound Bottom")
		(35 "F.Fab" user "Ref Des/Assembly Top")
		(33 "B.Fab" user "Ref Des/Assembly Bottom")
	)
	(footprint ""
		(layer "F.Cu")
		(at 136.652 -113.157)
		(property "Reference" "C8019"
			(at 0 0 0)
			(layer "F.SilkS")
			(hide yes)
			(effects
				(font
					(size 1.27 1.27)
				)
			)
		)
		(property "Value" ""
			(at 0 0 0)
			(layer "F.Fab")
			(effects
				(font
					(size 1.27 1.27)
				)
			)
		)
		(duplicate_pad_numbers_are_jumpers no)
		(fp_line
			(start -0.7874 -0.4064)
			(end 0.7874 -0.4064)
			(stroke
				(width 0.1524)
				(type default)
			)
			(layer "F.SilkS")
		)
		(fp_line
			(start -0.7874 0.4064)
			(end -0.7874 -0.4064)
			(stroke
				(width 0.1524)
				(type default)
			)
			(layer "F.SilkS")
		)
		(fp_line
			(start 0.7874 -0.4064)
			(end 0.7874 0.4064)
			(stroke
				(width 0.1524)
				(type default)
			)
			(layer "F.SilkS")
		)
		(fp_line
			(start 0.7874 0.4064)
			(end -0.7874 0.4064)
			(stroke
				(width 0.1524)
				(type default)
			)
			(layer "F.SilkS")
		)
		(fp_line
			(start -0.67945 -0.305054)
			(end -0.12065 -0.305054)
			(stroke
				(width 0.1)
				(type default)
			)
			(layer "F.Fab")
		)
		(fp_line
			(start -0.67945 0.3048)
			(end -0.67945 -0.305054)
			(stroke
				(width 0.1)
				(type default)
			)
			(layer "F.Fab")
		)
		(fp_line
			(start -0.12065 -0.305054)
			(end -0.12065 -0.2794)
			(stroke
				(width 0.1)
				(type default)
			)
			(layer "F.Fab")
		)
		(fp_line
			(start -0.12065 -0.2794)
			(end 0.12065 -0.2794)
			(stroke
				(width 0.1)
				(type default)
			)
			(layer "F.Fab")
		)
		(fp_line
			(start -0.12065 0.2794)
			(end -0.12065 0.3048)
			(stroke
				(width 0.1)
				(type default)
			)
			(layer "F.Fab")
		)
		(fp_line
			(start -0.12065 0.3048)
			(end -0.67945 0.3048)
			(stroke
				(width 0.1)
				(type default)
			)
			(layer "F.Fab")
		)
		(fp_line
			(start 0.120396 0.2794)
			(end -0.12065 0.2794)
			(stroke
				(width 0.1)
				(type default)
			)
			(layer "F.Fab")
		)
		(fp_line
			(start 0.120396 0.3048)
			(end 0.120396 0.2794)
			(stroke
				(width 0.1)
				(type default)
			)
			(layer "F.Fab")
		)
		(fp_line
			(start 0.12065 -0.3048)
			(end 0.67945 -0.3048)
			(stroke
				(width 0.1)
				(type default)
			)
			(layer "F.Fab")
		)
		(fp_line
			(start 0.12065 -0.2794)
			(end 0.12065 -0.3048)
			(stroke
				(width 0.1)
				(type default)
			)
			(layer "F.Fab")
		)
		(fp_line
			(start 0.67945 -0.3048)
			(end 0.67945 0.3048)
			(stroke
				(width 0.1)
				(type default)
			)
			(layer "F.Fab")
		)
		(fp_line
			(start 0.67945 0.3048)
			(end 0.120396 0.3048)
			(stroke
				(width 0.1)
				(type default)
			)
			(layer "F.Fab")
		)
		(pad "1" smd circle
			(at -0.40005 0)
			(size 0 0)
			(layers "F.Cu" "F.Mask" "F.Paste")
			(net "P12V_AUX")
		)
		(pad "2" smd circle
			(at 0.40005 0)
			(size 0 0)
			(layers "F.Cu" "F.Mask" "F.Paste")
			(net "GND")
		)
	)
	(footprint ""
		(layer "F.Cu")
		(at 333.629 -160.909 90)
		(property "Reference" "PC115"
			(at -0.889 -3.52933 90)
			(unlocked yes)
			(layer "F.SilkS")
			(effects
				(font
					(size 0.7874 0.5842)
					(thickness 0.1524)
				)
				(justify left)
			)
		)
		(property "Value" ""
			(at 0 0 90)
			(layer "F.Fab")
			(effects
				(font
					(size 1.27 1.27)
				)
			)
		)
		(duplicate_pad_numbers_are_jumpers no)
		(fp_line
			(start 2.750058 -2.750058)
			(end -1.988058 -2.750058)
			(stroke
				(width 0.1524)
				(type default)
			)
			(layer "F.SilkS")
		)
		(fp_line
			(start -1.988058 -2.750058)
			(end -2.750058 -1.988058)
			(stroke
				(width 0.1524)
				(type default)
			)
			(layer "F.SilkS")
		)
		(fp_line
			(start -2.750058 -1.988058)
			(end -2.750058 -0.9398)
			(stroke
				(width 0.1524)
				(type default)
			)
			(layer "F.SilkS")
		)
		(fp_line
			(start 2.750058 -0.9398)
			(end 2.750058 -2.750058)
			(stroke
				(width 0.1524)
				(type default)
			)
			(layer "F.SilkS")
		)
		(fp_line
			(start -2.750058 0.9398)
			(end -2.750058 1.988058)
			(stroke
				(width 0.1524)
				(type default)
			)
			(layer "F.SilkS")
		)
		(fp_line
			(start -2.750058 1.988058)
			(end -1.988058 2.750058)
			(stroke
				(width 0.1524)
				(type default)
			)
			(layer "F.SilkS")
		)
		(fp_line
			(start 2.750058 2.750058)
			(end 2.750058 0.9398)
			(stroke
				(width 0.1524)
				(type default)
			)
			(layer "F.SilkS")
		)
		(fp_line
			(start -1.988058 2.750058)
			(end 2.750058 2.750058)
			(stroke
				(width 0.1524)
				(type default)
			)
			(layer "F.SilkS")
		)
		(fp_line
			(start 2.750058 -2.750058)
			(end -2.750058 -2.750058)
			(stroke
				(width 0.1)
				(type default)
			)
			(layer "F.Fab")
		)
		(fp_line
			(start -2.750058 -2.750058)
			(end -2.750058 2.750058)
			(stroke
				(width 0.1)
				(type default)
			)
			(layer "F.Fab")
		)
		(fp_line
			(start 2.750058 2.750058)
			(end 2.750058 -2.750058)
			(stroke
				(width 0.1)
				(type default)
			)
			(layer "F.Fab")
		)
		(fp_line
			(start -2.750058 2.750058)
			(end 2.750058 2.750058)
			(stroke
				(width 0.1)
				(type default)
			)
			(layer "F.Fab")
		)
		(pad "1" smd rect
			(at -2.199894 0 180)
			(size 1.6002 3.0226)
			(layers "F.Cu" "F.Mask" "F.Paste")
			(net "PVDD18_S5_P0")
		)
		(pad "2" smd rect
			(at 2.199894 0 180)
			(size 1.6002 3.0226)
			(layers "F.Cu" "F.Mask" "F.Paste")
			(net "GND")
		)
	)
	(footprint ""
		(layer "F.Cu")
		(at 63.15075 -193.594228)
		(property "Reference" "TP14"
			(at 0 0 0)
			(layer "F.SilkS")
			(hide yes)
			(effects
				(font
					(size 1.27 1.27)
				)
			)
		)
		(property "Value" ""
			(at 0 0 0)
			(layer "F.Fab")
			(effects
				(font
					(size 1.27 1.27)
				)
			)
		)
		(duplicate_pad_numbers_are_jumpers no)
		(pad "1" smd circle
			(at 0 0)
			(size 0.762 0.762)
			(layers "F.Cu" "F.Mask" "F.Paste")
			(net "VSENSE_PVDD18_S5_P1_DN")
		)
	)
	(footprint ""
		(layer "F.Cu")
		(at 303.861724 -406.133808)
		(property "Reference" "C556"
			(at 0 0 0)
			(layer "F.SilkS")
			(hide yes)
			(effects
				(font
					(size 1.27 1.27)
				)
			)
		)
		(property "Value" ""
			(at 0 0 0)
			(layer "F.Fab")
			(effects
				(font
					(size 1.27 1.27)
				)
			)
		)
		(duplicate_pad_numbers_are_jumpers no)
		(fp_line
			(start -1.524 -0.762)
			(end 1.524 -0.762)
			(stroke
				(width 0.1524)
				(type default)
			)
			(layer "F.SilkS")
		)
		(fp_line
			(start -1.524 0.762)
			(end -1.524 -0.762)
			(stroke
				(width 0.1524)
				(type default)
			)
			(layer "F.SilkS")
		)
		(fp_line
			(start 1.524 -0.762)
			(end 1.524 0.762)
			(stroke
				(width 0.1524)
				(type default)
			)
			(layer "F.SilkS")
		)
		(fp_line
			(start 1.524 0.762)
			(end -1.524 0.762)
			(stroke
				(width 0.1524)
				(type default)
			)
			(layer "F.SilkS")
		)
		(fp_line
			(start -1.1049 -0.724916)
			(end -1.1049 0.724916)
			(stroke
				(width 0.1)
				(type default)
			)
			(layer "F.Fab")
		)
		(fp_line
			(start -1.1049 0.724916)
			(end 1.1049 0.724916)
			(stroke
				(width 0.1)
				(type default)
			)
			(layer "F.Fab")
		)
		(fp_line
			(start 1.1049 -0.724916)
			(end -1.1049 -0.724916)
			(stroke
				(width 0.1)
				(type default)
			)
			(layer "F.Fab")
		)
		(fp_line
			(start 1.1049 0.724916)
			(end 1.1049 -0.724916)
			(stroke
				(width 0.1)
				(type default)
			)
			(layer "F.Fab")
		)
		(pad "1" smd rect
			(at -0.889 0 180)
			(size 1.016 1.27)
			(layers "F.Cu" "F.Mask" "F.Paste")
			(net "P0V9_CPU0_RT0_2A")
		)
		(pad "2" smd rect
			(at 0.889 0 180)
			(size 1.016 1.27)
			(layers "F.Cu" "F.Mask" "F.Paste")
			(net "GND")
		)
	)
)
